(kicad_pcb
	(version 20221018)
	(generator pcbnew)
	(general
    (thickness 1.7403)
  )
	(paper "A4")
	(title_block
    (title "Data Center RDIMM DDR4 Tester")
    (date "2024-09-30")
    (rev "1.2.4")
		(comment 9 "footprints 57-66 of 690")
	)
	(layers
    (0 "F.Cu" signal)
    (1 "In1.Cu" power)
    (2 "In2.Cu" signal)
    (3 "In3.Cu" power)
    (4 "In4.Cu" power)
    (5 "In5.Cu" signal)
    (6 "In6.Cu" power)
    (7 "In7.Cu" signal)
    (8 "In8.Cu" power)
    (9 "In9.Cu" signal)
    (10 "In10.Cu" power)
    (31 "B.Cu" signal)
    (32 "B.Adhes" user "B.Adhesive")
    (33 "F.Adhes" user "F.Adhesive")
    (34 "B.Paste" user)
    (35 "F.Paste" user)
    (36 "B.SilkS" user "B.Silkscreen")
    (37 "F.SilkS" user "F.Silkscreen")
    (38 "B.Mask" user)
    (39 "F.Mask" user)
    (40 "Dwgs.User" user "User.Drawings")
    (41 "Cmts.User" user "User.Comments")
    (42 "Eco1.User" user "User.Eco1")
    (43 "Eco2.User" user "User.Eco2")
    (44 "Edge.Cuts" user)
    (45 "Margin" user)
    (46 "B.CrtYd" user "B.Courtyard")
    (47 "F.CrtYd" user "F.Courtyard")
    (48 "B.Fab" user)
    (49 "F.Fab" user)
  )
	(footprint "data-center-rdimm-ddr4-tester-footprints:R_0402_1005Metric" (layer "F.Cu")
    (at 135.1 121.325 90)
    (descr "Resistor SMD 0402")
    (tags "resistor SMD 0402")
    (property "Author" "Antmicro")
    (property "License" "Apache-2.0")
    (property "MPN" "CR0402-FX-2002GLF")
    (property "Manufacturer" "Bourns")
    (property "Sheetfile" "interfaces.kicad_sch")
    (property "Sheetname" "Interfaces")
    (property "Tolerance" "1%")
    (property "Val" "20k")
    (property "ki_description" "20k resistor in 0402 package with 1% tolerance")
    (attr smd)
    (fp_text reference "R134" (at -3.675 0.35 90) (layer "F.SilkS")
        (effects (font (size 0.7 0.7) (thickness 0.15)) (justify left bottom))
    )
    (fp_text value "R_20k_0402" (at 0 1.4 90) (layer "F.Fab") hide
        (effects (font (size 0.7 0.7) (thickness 0.15)) (justify left bottom))
    )
    (fp_text user "License: Apache-2.0" (at -0.95 5.169 90) (layer "F.Fab") hide
        (effects (font (size 0.7 0.7) (thickness 0.15)) (justify left bottom))
    )
    (fp_text user "${REFERENCE}" (at -0.95 3.168 90) (layer "F.Fab") hide
        (effects (font (size 0.7 0.7) (thickness 0.15)) (justify left bottom))
    )
    (fp_text user "Author: Antmicro" (at -0.95 4.169 90) (layer "F.Fab") hide
        (effects (font (size 0.7 0.7) (thickness 0.15)) (justify left bottom))
    )
    (fp_rect (start -0.93 -0.47) (end 0.93 0.47)
      (stroke (width 0.05) (type solid)) (fill none) (layer "F.CrtYd"))
    (fp_rect (start -0.5 -0.25) (end 0.5 0.25)
      (stroke (width 0.15) (type solid)) (fill none) (layer "F.Fab"))
    (pad "1" smd roundrect (at -0.485 0 90) (size 0.59 0.64) (layers "F.Cu" "F.Paste" "F.Mask") (roundrect_rratio 0.25)
      (net 143 "3V3_SYS") (pintype "passive"))
    (pad "2" smd roundrect (at 0.485 0 90) (size 0.59 0.64) (layers "F.Cu" "F.Paste" "F.Mask") (roundrect_rratio 0.25)
      (net 84 "SD_CLK") (pintype "passive"))
  )
	(footprint "data-center-rdimm-ddr4-tester-footprints:R_0402_1005Metric" (layer "F.Cu")
    (at 132.9 121.325 90)
    (descr "Resistor SMD 0402")
    (tags "resistor SMD 0402")
    (property "Author" "Antmicro")
    (property "License" "Apache-2.0")
    (property "MPN" "CR0402-FX-2002GLF")
    (property "Manufacturer" "Bourns")
    (property "Sheetfile" "interfaces.kicad_sch")
    (property "Sheetname" "Interfaces")
    (property "Tolerance" "1%")
    (property "Val" "20k")
    (property "ki_description" "20k resistor in 0402 package with 1% tolerance")
    (attr smd)
    (fp_text reference "R135" (at -3.675 0.35 90) (layer "F.SilkS")
        (effects (font (size 0.7 0.7) (thickness 0.15)) (justify left bottom))
    )
    (fp_text value "R_20k_0402" (at 0 1.4 90) (layer "F.Fab") hide
        (effects (font (size 0.7 0.7) (thickness 0.15)) (justify left bottom))
    )
    (fp_text user "License: Apache-2.0" (at -0.95 5.169 90) (layer "F.Fab") hide
        (effects (font (size 0.7 0.7) (thickness 0.15)) (justify left bottom))
    )
    (fp_text user "Author: Antmicro" (at -0.95 4.169 90) (layer "F.Fab") hide
        (effects (font (size 0.7 0.7) (thickness 0.15)) (justify left bottom))
    )
    (fp_text user "${REFERENCE}" (at -0.95 3.168 90) (layer "F.Fab") hide
        (effects (font (size 0.7 0.7) (thickness 0.15)) (justify left bottom))
    )
    (fp_rect (start -0.93 -0.47) (end 0.93 0.47)
      (stroke (width 0.05) (type solid)) (fill none) (layer "F.CrtYd"))
    (fp_rect (start -0.5 -0.25) (end 0.5 0.25)
      (stroke (width 0.15) (type solid)) (fill none) (layer "F.Fab"))
    (pad "1" smd roundrect (at -0.485 0 90) (size 0.59 0.64) (layers "F.Cu" "F.Paste" "F.Mask") (roundrect_rratio 0.25)
      (net 143 "3V3_SYS") (pintype "passive"))
    (pad "2" smd roundrect (at 0.485 0 90) (size 0.59 0.64) (layers "F.Cu" "F.Paste" "F.Mask") (roundrect_rratio 0.25)
      (net 85 "SD_CMD") (pintype "passive"))
  )
	(footprint "data-center-rdimm-ddr4-tester-footprints:R_0402_1005Metric" (layer "F.Cu")
    (at 138.35 121.325 90)
    (descr "Resistor SMD 0402")
    (tags "resistor SMD 0402")
    (property "Author" "Antmicro")
    (property "License" "Apache-2.0")
    (property "MPN" "CR0402-FX-2002GLF")
    (property "Manufacturer" "Bourns")
    (property "Sheetfile" "interfaces.kicad_sch")
    (property "Sheetname" "Interfaces")
    (property "Tolerance" "1%")
    (property "Val" "20k")
    (property "ki_description" "20k resistor in 0402 package with 1% tolerance")
    (attr smd)
    (fp_text reference "R132" (at -3.685 0.335 90) (layer "F.SilkS")
        (effects (font (size 0.7 0.7) (thickness 0.15)) (justify left bottom))
    )
    (fp_text value "R_20k_0402" (at 0 1.4 90) (layer "F.Fab") hide
        (effects (font (size 0.7 0.7) (thickness 0.15)) (justify left bottom))
    )
    (fp_text user "Author: Antmicro" (at -0.95 4.169 90) (layer "F.Fab") hide
        (effects (font (size 0.7 0.7) (thickness 0.15)) (justify left bottom))
    )
    (fp_text user "License: Apache-2.0" (at -0.95 5.169 90) (layer "F.Fab") hide
        (effects (font (size 0.7 0.7) (thickness 0.15)) (justify left bottom))
    )
    (fp_text user "${REFERENCE}" (at -0.95 3.168 90) (layer "F.Fab") hide
        (effects (font (size 0.7 0.7) (thickness 0.15)) (justify left bottom))
    )
    (fp_rect (start -0.93 -0.47) (end 0.93 0.47)
      (stroke (width 0.05) (type solid)) (fill none) (layer "F.CrtYd"))
    (fp_rect (start -0.5 -0.25) (end 0.5 0.25)
      (stroke (width 0.15) (type solid)) (fill none) (layer "F.Fab"))
    (pad "1" smd roundrect (at -0.485 0 90) (size 0.59 0.64) (layers "F.Cu" "F.Paste" "F.Mask") (roundrect_rratio 0.25)
      (net 143 "3V3_SYS") (pintype "passive"))
    (pad "2" smd roundrect (at 0.485 0 90) (size 0.59 0.64) (layers "F.Cu" "F.Paste" "F.Mask") (roundrect_rratio 0.25)
      (net 82 "SD_DAT1") (pintype "passive"))
  )
	(footprint "data-center-rdimm-ddr4-tester-footprints:C_0603_1608Metric" (layer "F.Cu")
    (at 116.661328 103.997157 180)
    (descr "Capacitor SMD 0603")
    (tags "capacitor 0603")
    (property "Author" "Antmicro")
    (property "Dielectric" "")
    (property "License" "Apache-2.0")
    (property "MPN" "C1608X5R1E106M080AC")
    (property "Manufacturer" "TDK")
    (property "Sheetfile" "supply.kicad_sch")
    (property "Sheetname" "Supply")
    (property "Val" "10u/25V")
    (property "Voltage" "")
    (property "ki_description" " ")
    (attr smd)
    (fp_text reference "C28" (at 1.261328 -1.652843 270) (layer "F.SilkS")
        (effects (font (size 0.7 0.7) (thickness 0.15)) (justify left bottom))
    )
    (fp_text value "C_10u_25V_0603" (at 0 1.6 180) (layer "F.Fab") hide
        (effects (font (size 0.7 0.7) (thickness 0.15)) (justify left bottom))
    )
    (fp_text user "License: Apache-2.0" (at -1.682 5.895 180) (layer "F.Fab") hide
        (effects (font (size 0.7 0.7) (thickness 0.15)) (justify left bottom))
    )
    (fp_text user "Author: Antmicro" (at -1.682 4.894 180) (layer "F.Fab") hide
        (effects (font (size 0.7 0.7) (thickness 0.15)) (justify left bottom))
    )
    (fp_text user "${REFERENCE}" (at -1.682 3.895 180) (layer "F.Fab") hide
        (effects (font (size 0.7 0.7) (thickness 0.15)) (justify left bottom))
    )
    (fp_line (start -0.3 -0.3) (end 0.3 -0.3)
      (stroke (width 0.15) (type solid)) (layer "F.SilkS"))
    (fp_line (start -0.3 0.3) (end 0.3 0.3)
      (stroke (width 0.15) (type solid)) (layer "F.SilkS"))
    (fp_rect (start -1.24 -0.7) (end 1.24 0.7)
      (stroke (width 0.05) (type solid)) (fill none) (layer "F.CrtYd"))
    (fp_rect (start -0.8 -0.4) (end 0.8 0.4)
      (stroke (width 0.15) (type solid)) (fill none) (layer "F.Fab"))
    (pad "1" smd roundrect (at -0.7 0 180) (size 0.6 0.8) (layers "F.Cu" "F.Paste" "F.Mask") (roundrect_rratio 0.2)
      (net 103 "VIN") (pintype "passive"))
    (pad "2" smd roundrect (at 0.7 0 180) (size 0.6 0.8) (layers "F.Cu" "F.Paste" "F.Mask") (roundrect_rratio 0.2)
      (net 9 "GND") (pintype "passive"))
  )
	(footprint "data-center-rdimm-ddr4-tester-footprints:FB_0603_1608Metric" (layer "F.Cu")
    (at 142.306328 116.527157 180)
    (property "Author" "Antmicro")
    (property "License" "Apache-2.0")
    (property "MPN" "BLM18AG601SN1D")
    (property "Manufacturer" "Murata")
    (property "Sheetfile" "interfaces.kicad_sch")
    (property "Sheetname" "Interfaces")
    (property "ki_description" "Ferrite Beads WE-TMSB Suppression 240Ohm 200mA ")
    (property "ki_keywords" " Multilayer Suppression Beads ")
    (attr smd)
    (fp_text reference "FB4" (at 0.706328 -3.582843 180) (layer "F.SilkS")
        (effects (font (size 0.7 0.7) (thickness 0.15)) (justify left bottom))
    )
    (fp_text value "FB_600Z_0.5A_0603" (at 0 1.7 180) (layer "F.Fab") hide
        (effects (font (size 0.7 0.7) (thickness 0.15)) (justify left bottom))
    )
    (fp_text user "Author: Antmicro" (at -1.653 3.162 180) (layer "F.Fab") hide
        (effects (font (size 0.7 0.7) (thickness 0.15)) (justify left bottom))
    )
    (fp_text user "License: Apache-2.0" (at -1.653 5.9 180) (layer "F.Fab") hide
        (effects (font (size 0.7 0.7) (thickness 0.15)) (justify left bottom))
    )
    (fp_text user "${REFERENCE}" (at -1.653 4.6 180) (layer "F.Fab") hide
        (effects (font (size 0.7 0.7) (thickness 0.15)) (justify left bottom))
    )
    (fp_line (start -0.196 -0.408) (end 0.193 -0.408)
      (stroke (width 0.15) (type solid)) (layer "F.SilkS"))
    (fp_line (start -0.196 0.406) (end 0.193 0.406)
      (stroke (width 0.15) (type solid)) (layer "F.SilkS"))
    (fp_rect (start -1.42 -0.69) (end 1.42 0.69)
      (stroke (width 0.05) (type solid)) (fill none) (layer "F.CrtYd"))
    (fp_line (start -0.803 0.406) (end -0.803 -0.408)
      (stroke (width 0.15) (type solid)) (layer "F.Fab"))
    (fp_line (start 0.8 -0.408) (end -0.803 -0.408)
      (stroke (width 0.15) (type solid)) (layer "F.Fab"))
    (fp_line (start 0.8 -0.408) (end 0.8 0.406)
      (stroke (width 0.15) (type solid)) (layer "F.Fab"))
    (fp_line (start 0.8 0.406) (end -0.803 0.406)
      (stroke (width 0.15) (type solid)) (layer "F.Fab"))
    (pad "1" smd roundrect (at -0.891 0 180) (size 0.762 1.09) (layers "F.Cu" "F.Paste" "F.Mask") (roundrect_rratio 0.15)
      (net 143 "3V3_SYS") (pintype "passive"))
    (pad "2" smd roundrect (at 0.888 0 180) (size 0.762 1.09) (layers "F.Cu" "F.Paste" "F.Mask") (roundrect_rratio 0.15)
      (net 75 "Net-(U7-V_{PLL})") (pintype "passive"))
  )
	(footprint "data-center-rdimm-ddr4-tester-footprints:C_0402_1005Metric" (layer "F.Cu")
    (at 137.536328 117.372157 90)
    (descr "Capacitor SMD 0402")
    (tags "capacitor SMD 0402")
    (property "Author" "Antmicro")
    (property "Dielectric" "")
    (property "License" "Apache-2.0")
    (property "MPN" "MC0402N180J500CT")
    (property "Manufacturer" "Multicomp")
    (property "Sheetfile" "interfaces.kicad_sch")
    (property "Sheetname" "Interfaces")
    (property "Val" "18p")
    (property "Voltage" "")
    (property "ki_description" " ")
    (attr smd)
    (fp_text reference "C193" (at -2.827843 2.813672 90) (layer "F.SilkS")
        (effects (font (size 0.7 0.7) (thickness 0.15)) (justify left bottom))
    )
    (fp_text value "C_18p_0402" (at 0 1.4 90) (layer "F.Fab") hide
        (effects (font (size 0.7 0.7) (thickness 0.15)) (justify left bottom))
    )
    (fp_text user "${REFERENCE}" (at -0.932 3.168 90) (layer "F.Fab") hide
        (effects (font (size 0.7 0.7) (thickness 0.15)) (justify left bottom))
    )
    (fp_text user "License: Apache-2.0" (at -0.932 5.17 90) (layer "F.Fab") hide
        (effects (font (size 0.7 0.7) (thickness 0.15)) (justify left bottom))
    )
    (fp_text user "Author: Antmicro" (at -0.932 4.17 90) (layer "F.Fab") hide
        (effects (font (size 0.7 0.7) (thickness 0.15)) (justify left bottom))
    )
    (fp_rect (start -0.94 -0.47) (end 0.94 0.47)
      (stroke (width 0.05) (type solid)) (fill none) (layer "F.CrtYd"))
    (fp_rect (start -0.499 -0.249) (end 0.499 0.249)
      (stroke (width 0.15) (type solid)) (fill none) (layer "F.Fab"))
    (pad "1" smd roundrect (at -0.484 0 90) (size 0.59 0.64) (layers "F.Cu" "F.Paste" "F.Mask") (roundrect_rratio 0.25)
      (net 81 "Net-(U7-OSCO)") (pintype "passive"))
    (pad "2" smd roundrect (at 0.484 0 90) (size 0.59 0.64) (layers "F.Cu" "F.Paste" "F.Mask") (roundrect_rratio 0.25)
      (net 9 "GND") (pintype "passive"))
  )
	(footprint "data-center-rdimm-ddr4-tester-footprints:R_0402_1005Metric" (layer "F.Cu")
    (at 118.411328 116.622157 180)
    (descr "Resistor SMD 0402")
    (tags "resistor SMD 0402")
    (property "Author" "Antmicro")
    (property "License" "Apache-2.0")
    (property "MPN" "CR0402-FX-5362GLF")
    (property "Manufacturer" "Bourns")
    (property "Sheetfile" "supply.kicad_sch")
    (property "Sheetname" "Supply")
    (property "Tolerance" "1%")
    (property "Val" "53k6")
    (property "ki_description" "53k6 resistor in 0402 package with 1% tolerance")
    (attr smd)
    (fp_text reference "R127" (at 5.151328 -3.597843 180) (layer "F.SilkS")
        (effects (font (size 0.7 0.7) (thickness 0.15)) (justify left bottom))
    )
    (fp_text value "R_53k6_0402" (at 0 1.4 180) (layer "F.Fab") hide
        (effects (font (size 0.7 0.7) (thickness 0.15)) (justify left bottom))
    )
    (fp_text user "Author: Antmicro" (at -0.95 4.169 180) (layer "F.Fab") hide
        (effects (font (size 0.7 0.7) (thickness 0.15)) (justify left bottom))
    )
    (fp_text user "${REFERENCE}" (at -0.95 3.168 180) (layer "F.Fab") hide
        (effects (font (size 0.7 0.7) (thickness 0.15)) (justify left bottom))
    )
    (fp_text user "License: Apache-2.0" (at -0.95 5.169 180) (layer "F.Fab") hide
        (effects (font (size 0.7 0.7) (thickness 0.15)) (justify left bottom))
    )
    (fp_rect (start -0.93 -0.47) (end 0.93 0.47)
      (stroke (width 0.05) (type solid)) (fill none) (layer "F.CrtYd"))
    (fp_rect (start -0.5 -0.25) (end 0.5 0.25)
      (stroke (width 0.15) (type solid)) (fill none) (layer "F.Fab"))
    (pad "1" smd roundrect (at -0.485 0 180) (size 0.59 0.64) (layers "F.Cu" "F.Paste" "F.Mask") (roundrect_rratio 0.25)
      (net 118 "Net-(R126-Pad2)") (pintype "passive"))
    (pad "2" smd roundrect (at 0.485 0 180) (size 0.59 0.64) (layers "F.Cu" "F.Paste" "F.Mask") (roundrect_rratio 0.25)
      (net 110 "Net-(IC1-FB)") (pintype "passive"))
  )
	(footprint "data-center-rdimm-ddr4-tester-footprints:C_0603_1608Metric" (layer "F.Cu")
    (at 116.036328 89.122157 180)
    (descr "Capacitor SMD 0603")
    (tags "capacitor 0603")
    (property "Author" "Antmicro")
    (property "Dielectric" "")
    (property "License" "Apache-2.0")
    (property "MPN" "GRM188R60J226MEA0D")
    (property "Manufacturer" "Murata")
    (property "Sheetfile" "supply.kicad_sch")
    (property "Sheetname" "Supply")
    (property "Val" "22u")
    (property "Voltage" "")
    (property "ki_description" " ")
    (attr smd)
    (fp_text reference "C42" (at 1.636328 13.392157 180) (layer "F.SilkS")
        (effects (font (size 0.7 0.7) (thickness 0.15)) (justify left bottom))
    )
    (fp_text value "C_22u_0603" (at 0 1.6 180) (layer "F.Fab") hide
        (effects (font (size 0.7 0.7) (thickness 0.15)) (justify left bottom))
    )
    (fp_text user "Author: Antmicro" (at -1.682 4.894 180) (layer "F.Fab") hide
        (effects (font (size 0.7 0.7) (thickness 0.15)) (justify left bottom))
    )
    (fp_text user "License: Apache-2.0" (at -1.682 5.895 180) (layer "F.Fab") hide
        (effects (font (size 0.7 0.7) (thickness 0.15)) (justify left bottom))
    )
    (fp_text user "${REFERENCE}" (at -1.682 3.895 180) (layer "F.Fab") hide
        (effects (font (size 0.7 0.7) (thickness 0.15)) (justify left bottom))
    )
    (fp_line (start -0.3 -0.3) (end 0.3 -0.3)
      (stroke (width 0.15) (type solid)) (layer "F.SilkS"))
    (fp_line (start -0.3 0.3) (end 0.3 0.3)
      (stroke (width 0.15) (type solid)) (layer "F.SilkS"))
    (fp_rect (start -1.24 -0.7) (end 1.24 0.7)
      (stroke (width 0.05) (type solid)) (fill none) (layer "F.CrtYd"))
    (fp_rect (start -0.8 -0.4) (end 0.8 0.4)
      (stroke (width 0.15) (type solid)) (fill none) (layer "F.Fab"))
    (pad "1" smd roundrect (at -0.7 0 180) (size 0.6 0.8) (layers "F.Cu" "F.Paste" "F.Mask") (roundrect_rratio 0.2)
      (net 301 "VDD1V2") (pintype "passive"))
    (pad "2" smd roundrect (at 0.7 0 180) (size 0.6 0.8) (layers "F.Cu" "F.Paste" "F.Mask") (roundrect_rratio 0.2)
      (net 9 "GND") (pintype "passive"))
  )
	(footprint "data-center-rdimm-ddr4-tester-footprints:C_0603_1608Metric" (layer "F.Cu")
    (at 116.036328 90.622157 180)
    (descr "Capacitor SMD 0603")
    (tags "capacitor 0603")
    (property "Author" "Antmicro")
    (property "Dielectric" "")
    (property "License" "Apache-2.0")
    (property "MPN" "GRM188R60J226MEA0D")
    (property "Manufacturer" "Murata")
    (property "Sheetfile" "supply.kicad_sch")
    (property "Sheetname" "Supply")
    (property "Val" "22u")
    (property "Voltage" "")
    (property "ki_description" " ")
    (attr smd)
    (fp_text reference "C41" (at 1.626328 13.922157 180) (layer "F.SilkS")
        (effects (font (size 0.7 0.7) (thickness 0.15)) (justify left bottom))
    )
    (fp_text value "C_22u_0603" (at 0 1.6 180) (layer "F.Fab") hide
        (effects (font (size 0.7 0.7) (thickness 0.15)) (justify left bottom))
    )
    (fp_text user "Author: Antmicro" (at -1.682 4.894 180) (layer "F.Fab") hide
        (effects (font (size 0.7 0.7) (thickness 0.15)) (justify left bottom))
    )
    (fp_text user "License: Apache-2.0" (at -1.682 5.895 180) (layer "F.Fab") hide
        (effects (font (size 0.7 0.7) (thickness 0.15)) (justify left bottom))
    )
    (fp_text user "${REFERENCE}" (at -1.682 3.895 180) (layer "F.Fab") hide
        (effects (font (size 0.7 0.7) (thickness 0.15)) (justify left bottom))
    )
    (fp_line (start -0.3 -0.3) (end 0.3 -0.3)
      (stroke (width 0.15) (type solid)) (layer "F.SilkS"))
    (fp_line (start -0.3 0.3) (end 0.3 0.3)
      (stroke (width 0.15) (type solid)) (layer "F.SilkS"))
    (fp_rect (start -1.24 -0.7) (end 1.24 0.7)
      (stroke (width 0.05) (type solid)) (fill none) (layer "F.CrtYd"))
    (fp_rect (start -0.8 -0.4) (end 0.8 0.4)
      (stroke (width 0.15) (type solid)) (fill none) (layer "F.Fab"))
    (pad "1" smd roundrect (at -0.7 0 180) (size 0.6 0.8) (layers "F.Cu" "F.Paste" "F.Mask") (roundrect_rratio 0.2)
      (net 301 "VDD1V2") (pintype "passive"))
    (pad "2" smd roundrect (at 0.7 0 180) (size 0.6 0.8) (layers "F.Cu" "F.Paste" "F.Mask") (roundrect_rratio 0.2)
      (net 9 "GND") (pintype "passive"))
  )
	(footprint "data-center-rdimm-ddr4-tester-footprints:R_0402_1005Metric" (layer "F.Cu")
    (at 221.803 112.867 90)
    (descr "Resistor SMD 0402")
    (tags "resistor SMD 0402")
    (property "Author" "Antmicro")
    (property "License" "Apache-2.0")
    (property "MPN" "CR0402-FX-1000GLF")
    (property "Manufacturer" "Bourns")
    (property "Sheetfile" "config-spi.kicad_sch")
    (property "Sheetname" "Config SPI flash")
    (property "Tolerance" "1%")
    (property "Val" "100R")
    (property "ki_description" "100R resistor in 0402 package with 1% tolerance")
    (attr smd)
    (fp_text reference "R10" (at 0.677 0.387 90) (layer "F.SilkS")
        (effects (font (size 0.7 0.7) (thickness 0.15)) (justify left bottom))
    )
    (fp_text value "R_100R_0402" (at 0 1.4 90) (layer "F.Fab") hide
        (effects (font (size 0.7 0.7) (thickness 0.15)) (justify left bottom))
    )
    (fp_text user "Author: Antmicro" (at -0.95 4.169 90) (layer "F.Fab") hide
        (effects (font (size 0.7 0.7) (thickness 0.15)) (justify left bottom))
    )
    (fp_text user "License: Apache-2.0" (at -0.95 5.169 90) (layer "F.Fab") hide
        (effects (font (size 0.7 0.7) (thickness 0.15)) (justify left bottom))
    )
    (fp_text user "${REFERENCE}" (at -0.95 3.168 90) (layer "F.Fab") hide
        (effects (font (size 0.7 0.7) (thickness 0.15)) (justify left bottom))
    )
    (fp_rect (start -0.93 -0.47) (end 0.93 0.47)
      (stroke (width 0.05) (type solid)) (fill none) (layer "F.CrtYd"))
    (fp_rect (start -0.5 -0.25) (end 0.5 0.25)
      (stroke (width 0.15) (type solid)) (fill none) (layer "F.Fab"))
    (pad "1" smd roundrect (at -0.485 0 90) (size 0.59 0.64) (layers "F.Cu" "F.Paste" "F.Mask") (roundrect_rratio 0.25)
      (net 143 "3V3_SYS") (pintype "passive"))
    (pad "2" smd roundrect (at 0.485 0 90) (size 0.59 0.64) (layers "F.Cu" "F.Paste" "F.Mask") (roundrect_rratio 0.25)
      (net 79 "PUDC_B") (pintype "passive"))
  )
)
